(kicad_pcb
	(version 20260206)
	(generator "pcbnew")
	(generator_version "10.0")
	(general
		(thickness 1.6)
		(legacy_teardrops no)
	)
	(paper "A4")
	(title_block
		(title "Wiwynn_Tioga_Pass_MB.brd")
		(comment 1 "Tioga Pass / footprints 1482-1485 of 4770")
	)
	(layers
		(0 "F.Cu" signal "TOP")
		(4 "In1.Cu" signal "L2GND")
		(6 "In2.Cu" signal "L3")
		(8 "In3.Cu" signal "L4GND")
		(10 "In4.Cu" signal "L5")
		(12 "In5.Cu" signal "L6GND")
		(14 "In6.Cu" signal "L7VCC")
		(16 "In7.Cu" signal "L8VCC")
		(18 "In8.Cu" signal "L9GND")
		(20 "In9.Cu" signal "L10")
		(22 "In10.Cu" signal "L11GND")
		(24 "In11.Cu" signal "L12")
		(26 "In12.Cu" signal "L13GND")
		(2 "B.Cu" signal "BOTTOM")
		(9 "F.Adhes" user "F.Adhesive")
		(11 "B.Adhes" user "B.Adhesive")
		(13 "F.Paste" user "Package Geometry/Pastemask Top")
		(15 "B.Paste" user "Package Geometry/Pastemask Bottom")
		(5 "F.SilkS" user "Ref Des/Silkscreen Top")
		(7 "B.SilkS" user "Ref Des/Silkscreen Bottom")
		(1 "F.Mask" user "Board Geometry/Soldermask Top")
		(3 "B.Mask" user "Board Geometry/Soldermask Bottom")
		(17 "Dwgs.User" user "User.Drawings")
		(19 "Cmts.User" user "User.Comments")
		(21 "Eco1.User" user "User.Eco1")
		(23 "Eco2.User" user "User.Eco2")
		(25 "Edge.Cuts" user "Board Geometry/Outline")
		(27 "Margin" user)
		(31 "F.CrtYd" user "Package Geometry/Place Bound Top")
		(29 "B.CrtYd" user "Package Geometry/Place Bound Bottom")
		(35 "F.Fab" user "Ref Des/Assembly Top")
		(33 "B.Fab" user "Ref Des/Assembly Bottom")
	)
	(footprint ""
		(layer "F.Cu")
		(at 351.505266 -156.4005 180)
		(property "Reference" "CT45"
			(at 0.7366 1.85293 0)
			(unlocked yes)
			(layer "F.SilkS")
			(effects
				(font
					(size 0.7874 0.5842)
					(thickness 0.1524)
				)
				(justify left)
			)
		)
		(property "Value" ""
			(at 0 0 180)
			(layer "F.Fab")
			(effects
				(font
					(size 1.27 1.27)
				)
			)
		)
		(duplicate_pad_numbers_are_jumpers no)
		(fp_poly
			(pts
				(xy 0.3048 -0.1016) (xy 0.3048 0.9906) (xy -0.3048 0.9906) (xy -0.3048 -0.1016)
			)
			(stroke
				(width 0)
				(type default)
			)
			(fill no)
			(layer "F.CrtYd")
		)
		(fp_line
			(start 0.3048 0.9906)
			(end 0.3048 -0.1016)
			(stroke
				(width 0.1)
				(type default)
			)
			(layer "F.Fab")
		)
		(fp_line
			(start 0.3048 -0.1016)
			(end -0.3048 -0.1016)
			(stroke
				(width 0.1)
				(type default)
			)
			(layer "F.Fab")
		)
		(fp_line
			(start -0.3048 0.9906)
			(end 0.3048 0.9906)
			(stroke
				(width 0.1)
				(type default)
			)
			(layer "F.Fab")
		)
		(fp_line
			(start -0.3048 -0.1016)
			(end -0.3048 0.9906)
			(stroke
				(width 0.1)
				(type default)
			)
			(layer "F.Fab")
		)
		(pad "1" smd rect
			(at 0 0 180)
			(size 0.508 0.508)
			(layers "F.Cu" "F.Mask" "F.Paste")
			(net "VR_PVDDQ_DEF_AIREF1")
		)
		(pad "2" smd rect
			(at 0 0.889 180)
			(size 0.508 0.508)
			(layers "F.Cu" "F.Mask" "F.Paste")
			(net "GND")
		)
		(zone
			(layer "F.Cu")
			(hatch none 0.5)
			(connect_pads
				(clearance 0)
			)
			(min_thickness 0.25)
			(keepout
				(tracks not_allowed)
				(vias allowed)
				(pads allowed)
				(copperpour not_allowed)
				(footprints allowed)
			)
			(placement
				(enabled no)
				(sheetname "")
			)
			(fill
				(thermal_gap 0.5)
				(thermal_bridge_width 0.5)
				(island_removal_mode 0)
			)
			(polygon
				(pts
					(xy 351.759266 -157.0355) (xy 351.251266 -157.0355) (xy 351.251266 -156.6545) (xy 351.759266 -156.6545)
				)
			)
		)
		(zone
			(layer "F.Cu")
			(hatch none 0.5)
			(connect_pads
				(clearance 0)
			)
			(min_thickness 0.25)
			(keepout
				(tracks allowed)
				(vias not_allowed)
				(pads allowed)
				(copperpour not_allowed)
				(footprints allowed)
			)
			(placement
				(enabled no)
				(sheetname "")
			)
			(fill
				(thermal_gap 0.5)
				(thermal_bridge_width 0.5)
				(island_removal_mode 0)
			)
			(polygon
				(pts
					(xy 351.759266 -156.6545) (xy 351.251266 -156.6545) (xy 351.251266 -157.0355) (xy 351.759266 -157.0355)
				)
			)
		)
	)
	(footprint ""
		(layer "F.Cu")
		(at 481.251006 -131.655312 90)
		(property "Reference" "J9B1"
			(at -2.522728 5.79501 0)
			(unlocked yes)
			(layer "B.SilkS")
			(effects
				(font
					(size 0.7874 0.5842)
					(thickness 0.1524)
				)
				(justify left mirror)
			)
		)
		(property "Value" ""
			(at 0 0 90)
			(layer "F.Fab")
			(effects
				(font
					(size 1.27 1.27)
				)
			)
		)
		(duplicate_pad_numbers_are_jumpers no)
		(fp_line
			(start 4.234942 -3.97002)
			(end 4.234942 -3.299968)
			(stroke
				(width 0.1524)
				(type default)
			)
			(layer "F.SilkS")
		)
		(fp_line
			(start -2.435098 -3.97002)
			(end 4.234942 -3.97002)
			(stroke
				(width 0.1524)
				(type default)
			)
			(layer "F.SilkS")
		)
		(fp_line
			(start -2.435098 -3.299968)
			(end -2.435098 -3.97002)
			(stroke
				(width 0.1524)
				(type default)
			)
			(layer "F.SilkS")
		)
		(fp_line
			(start 4.234942 -0.299974)
			(end 4.234942 6.75005)
			(stroke
				(width 0.1524)
				(type default)
			)
			(layer "F.SilkS")
		)
		(fp_line
			(start -2.435098 6.75005)
			(end -2.435098 -0.299974)
			(stroke
				(width 0.1524)
				(type default)
			)
			(layer "F.SilkS")
		)
		(fp_line
			(start -2.435098 10.500106)
			(end -2.435098 21.100034)
			(stroke
				(width 0.1524)
				(type default)
			)
			(layer "F.SilkS")
		)
		(fp_line
			(start 4.234942 21.100034)
			(end 4.234942 10.500106)
			(stroke
				(width 0.1524)
				(type default)
			)
			(layer "F.SilkS")
		)
		(fp_poly
			(pts
				(xy -3.922776 -0.556514) (xy -3.922776 0.459486) (xy -2.652776 -0.048514)
			)
			(stroke
				(width 0)
				(type default)
			)
			(fill yes)
			(layer "F.SilkS")
		)
		(fp_poly
			(pts
				(xy -4.303776 -0.556514) (xy -4.303776 0.459486) (xy -3.033776 -0.048514)
			)
			(stroke
				(width 0)
				(type default)
			)
			(fill yes)
			(layer "B.SilkS")
		)
		(fp_rect
			(start -2.435098 22.029928)
			(end 4.234942 -3.97002)
			(stroke
				(width 0)
				(type default)
			)
			(fill no)
			(layer "F.CrtYd")
		)
		(fp_poly
			(pts
				(xy -4.303776 -0.556514) (xy -4.303776 0.459486) (xy -3.033776 -0.048514)
			)
			(stroke
				(width 0)
				(type default)
			)
			(fill yes)
			(layer "B.Fab")
		)
		(fp_line
			(start 4.234942 -3.97002)
			(end -2.435098 -3.97002)
			(stroke
				(width 0.1)
				(type default)
			)
			(layer "F.Fab")
		)
		(fp_line
			(start -2.435098 -3.97002)
			(end -2.435098 22.029928)
			(stroke
				(width 0.1)
				(type default)
			)
			(layer "F.Fab")
		)
		(fp_line
			(start 4.234942 22.029928)
			(end 4.234942 -3.97002)
			(stroke
				(width 0.1)
				(type default)
			)
			(layer "F.Fab")
		)
		(fp_line
			(start -2.435098 22.029928)
			(end 4.234942 22.029928)
			(stroke
				(width 0.1)
				(type default)
			)
			(layer "F.Fab")
		)
		(fp_poly
			(pts
				(xy -4.303776 -0.556514) (xy -4.303776 0.459486) (xy -3.033776 -0.048514)
			)
			(stroke
				(width 0)
				(type default)
			)
			(fill yes)
			(layer "F.Fab")
		)
		(fp_text user "9"
			(at 1.18364 -4.63423 0)
			(unlocked yes)
			(layer "F.SilkS")
			(effects
				(font
					(size 0.7874 0.5842)
					(thickness 0.1524)
				)
				(justify left)
			)
		)
		(fp_text user "4"
			(at -3.109468 4.33705 0)
			(unlocked yes)
			(layer "F.SilkS")
			(effects
				(font
					(size 0.7874 0.5842)
					(thickness 0.1524)
				)
				(justify left)
			)
		)
		(fp_text user "5"
			(at 4.335018 7.315454 0)
			(unlocked yes)
			(layer "F.SilkS")
			(effects
				(font
					(size 0.7874 0.5842)
					(thickness 0.1524)
				)
				(justify left)
			)
		)
		(fp_text user "9"
			(at 3.319272 0.33401 0)
			(unlocked yes)
			(layer "B.SilkS")
			(effects
				(font
					(size 0.7874 0.5842)
					(thickness 0.1524)
				)
				(justify left mirror)
			)
		)
		(fp_text user " 4"
			(at -2.251964 6.809994 0)
			(unlocked yes)
			(layer "B.SilkS")
			(effects
				(font
					(size 0.7874 0.5842)
					(thickness 0.1524)
				)
				(justify left mirror)
			)
		)
		(fp_text user "5"
			(at 3.565398 7.61111 0)
			(unlocked yes)
			(layer "B.SilkS")
			(effects
				(font
					(size 0.7874 0.5842)
					(thickness 0.1524)
				)
				(justify left mirror)
			)
		)
		(fp_text user "9"
			(at 5.343144 -0.38608 90)
			(unlocked yes)
			(layer "B.Fab")
			(effects
				(font
					(size 0.635 0.635)
					(thickness 0.1524)
				)
				(justify left mirror)
			)
		)
		(fp_text user "4"
			(at -2.783332 7.02056 90)
			(unlocked yes)
			(layer "B.Fab")
			(effects
				(font
					(size 0.7874 0.5842)
					(thickness 0.1524)
				)
				(justify left mirror)
			)
		)
		(fp_text user "5"
			(at 5.291074 7.411212 90)
			(unlocked yes)
			(layer "B.Fab")
			(effects
				(font
					(size 0.7874 0.5842)
					(thickness 0.1524)
				)
				(justify left mirror)
			)
		)
		(fp_text user "9"
			(at 4.57327 -2.42316 90)
			(unlocked yes)
			(layer "F.Fab")
			(effects
				(font
					(size 0.7874 0.5842)
					(thickness 0.1524)
				)
				(justify left)
			)
		)
		(fp_text user "4"
			(at -3.105658 4.33832 0)
			(unlocked yes)
			(layer "F.Fab")
			(effects
				(font
					(size 0.7874 0.5842)
					(thickness 0.1524)
				)
				(justify left)
			)
		)
		(fp_text user "5"
			(at 4.882388 10.311384 0)
			(unlocked yes)
			(layer "F.Fab")
			(effects
				(font
					(size 0.7874 0.5842)
					(thickness 0.1524)
				)
				(justify left)
			)
		)
		(pad "1" thru_hole rect
			(at 0 0 90)
			(size 1.143 1.143)
			(drill 0.762)
			(layers "*.Cu" "*.Mask")
			(remove_unused_layers no)
			(net "P5V_USB")
			(clearance 0.127)
			(thermal_gap 0.127)
			(padstack
				(mode front_inner_back)
				(layer "Inner"
					(shape circle)
					(size 1.143 1.143)
					(clearance 0.127)
				)
				(layer "B.Cu"
					(shape rect)
					(size 1.143 1.143)
					(clearance 0.127)
				)
			)
		)
		(pad "2" thru_hole circle
			(at 0 2.500122 90)
			(size 1.143 1.143)
			(drill 0.762)
			(layers "*.Cu" "*.Mask")
			(remove_unused_layers no)
			(net "USB2_P01_ESD_DN")
			(clearance 0.127)
			(thermal_gap 0.127)
		)
		(pad "3" thru_hole circle
			(at 0 4.500118 90)
			(size 1.143 1.143)
			(drill 0.762)
			(layers "*.Cu" "*.Mask")
			(remove_unused_layers no)
			(net "USB2_P01_ESD_DP")
			(clearance 0.127)
			(thermal_gap 0.127)
		)
		(pad "4" thru_hole circle
			(at 0 6.999986 90)
			(size 1.143 1.143)
			(drill 0.762)
			(layers "*.Cu" "*.Mask")
			(remove_unused_layers no)
			(net "GND")
			(clearance 0.127)
			(thermal_gap 0.127)
		)
		(pad "5" thru_hole circle
			(at 1.800098 7.500112 90)
			(size 1.143 1.143)
			(drill 0.762)
			(layers "*.Cu" "*.Mask")
			(remove_unused_layers no)
			(net "SMB_DEBUG_STBY_LVC3_SCL_CONN")
			(clearance 0.127)
			(thermal_gap 0.127)
		)
		(pad "6" thru_hole circle
			(at 1.800098 5.500116 90)
			(size 1.143 1.143)
			(drill 0.762)
			(layers "*.Cu" "*.Mask")
			(remove_unused_layers no)
			(net "SMB_DEBUG_STBY_LVC3_SDA_CONN")
			(clearance 0.127)
			(thermal_gap 0.127)
		)
		(pad "7" thru_hole circle
			(at 1.800098 3.50012 90)
			(size 1.143 1.143)
			(drill 0.762)
			(layers "*.Cu" "*.Mask")
			(remove_unused_layers no)
			(net "DEBUG_CARD2_PRSNT")
			(clearance 0.127)
			(thermal_gap 0.127)
		)
		(pad "8" thru_hole circle
			(at 1.800098 1.500124 90)
			(size 1.143 1.143)
			(drill 0.762)
			(layers "*.Cu" "*.Mask")
			(remove_unused_layers no)
			(net "SPA_MID_DBG2_TX")
			(clearance 0.127)
			(thermal_gap 0.127)
		)
		(pad "9" thru_hole circle
			(at 1.800098 -0.500126 90)
			(size 1.143 1.143)
			(drill 0.762)
			(layers "*.Cu" "*.Mask")
			(remove_unused_layers no)
			(net "SPA_MID_DBG2_RX")
			(clearance 0.127)
			(thermal_gap 0.127)
		)
		(pad "MH1" thru_hole oval
			(at -1.810004 -1.869948 90)
			(size 1.1684 1.778)
			(drill oval 0.7874 1.397)
			(layers "*.Cu" "*.Mask")
			(remove_unused_layers no)
			(net "GND")
			(clearance 0.127)
			(thermal_gap 0.127)
		)
		(pad "MH2" thru_hole oval
			(at -1.810004 8.830056 90)
			(size 1.1684 2.4892)
			(drill oval 0.7874 2.1082)
			(layers "*.Cu" "*.Mask")
			(remove_unused_layers no)
			(net "GND")
			(clearance 0.127)
			(thermal_gap 0.127)
		)
		(pad "MH3" thru_hole oval
			(at 3.610102 8.830056 90)
			(size 1.1684 1.778)
			(drill oval 0.7874 1.397)
			(layers "*.Cu" "*.Mask")
			(remove_unused_layers no)
			(net "GND")
			(clearance 0.127)
			(thermal_gap 0.127)
		)
		(pad "MH4" thru_hole oval
			(at 3.610102 -1.869948 90)
			(size 1.1684 2.4892)
			(drill oval 0.7874 2.1082)
			(layers "*.Cu" "*.Mask")
			(remove_unused_layers no)
			(net "GND")
			(clearance 0.127)
			(thermal_gap 0.127)
		)
		(zone
			(layer "F.Cu")
			(hatch none 0.5)
			(connect_pads
				(clearance 0)
			)
			(min_thickness 0.25)
			(keepout
				(tracks not_allowed)
				(vias allowed)
				(pads allowed)
				(copperpour not_allowed)
				(footprints allowed)
			)
			(placement
				(enabled no)
				(sheetname "")
			)
			(fill
				(thermal_gap 0.5)
				(thermal_bridge_width 0.5)
				(island_removal_mode 0)
			)
			(polygon
				(pts
					(xy 479.580956 -130.555238) (xy 479.580956 -134.55523) (xy 477.58096 -134.55523) (xy 477.58096 -130.555238)
				)
			)
		)
		(zone
			(layer "F.Cu")
			(hatch none 0.5)
			(connect_pads
				(clearance 0)
			)
			(min_thickness 0.25)
			(keepout
				(tracks not_allowed)
				(vias allowed)
				(pads allowed)
				(copperpour not_allowed)
				(footprints allowed)
			)
			(placement
				(enabled no)
				(sheetname "")
			)
			(fill
				(thermal_gap 0.5)
				(thermal_bridge_width 0.5)
				(island_removal_mode 0)
			)
			(polygon
				(pts
					(xy 496.031012 -129.55524) (xy 496.031012 -135.555228) (xy 491.63097 -135.555228) (xy 491.63097 -134.40537)
					(xy 489.630974 -134.40537) (xy 489.630974 -130.705352) (xy 491.63097 -130.705352) (xy 491.63097 -129.55524)
				)
			)
		)
	)
	(footprint ""
		(layer "F.Cu")
		(at 183.167274 -10.91057 90)
		(property "Reference" "C6U8"
			(at 1.47828 0.78994 0)
			(unlocked yes)
			(layer "F.SilkS")
			(effects
				(font
					(size 0.4064 0.254)
					(thickness 0.1524)
				)
			)
		)
		(property "Value" ""
			(at 0 0 90)
			(layer "F.Fab")
			(effects
				(font
					(size 1.27 1.27)
				)
			)
		)
		(duplicate_pad_numbers_are_jumpers no)
		(fp_poly
			(pts
				(xy -0.7239 -0.2159) (xy 0.7239 -0.2159) (xy 0.7239 1.9939) (xy -0.7239 1.9939)
			)
			(stroke
				(width 0)
				(type default)
			)
			(fill no)
			(layer "F.CrtYd")
		)
		(fp_line
			(start 0.7239 -0.2159)
			(end -0.7239 -0.2159)
			(stroke
				(width 0.1)
				(type default)
			)
			(layer "F.Fab")
		)
		(fp_line
			(start -0.7239 -0.2159)
			(end -0.7239 1.9939)
			(stroke
				(width 0.1)
				(type default)
			)
			(layer "F.Fab")
		)
		(fp_line
			(start 0.7239 1.9939)
			(end 0.7239 -0.2159)
			(stroke
				(width 0.1)
				(type default)
			)
			(layer "F.Fab")
		)
		(fp_line
			(start -0.7239 1.9939)
			(end 0.7239 1.9939)
			(stroke
				(width 0.1)
				(type default)
			)
			(layer "F.Fab")
		)
		(pad "1" smd rect
			(at 0 0 90)
			(size 1.27 1.016)
			(layers "F.Cu" "F.Mask" "F.Paste")
			(net "VR_FET_SW_P12V_STBY_PVPP_GHJ")
		)
		(pad "2" smd rect
			(at 0 1.778 90)
			(size 1.27 1.016)
			(layers "F.Cu" "F.Mask" "F.Paste")
			(net "GND")
		)
		(zone
			(layer "F.Cu")
			(hatch none 0.5)
			(connect_pads
				(clearance 0)
			)
			(min_thickness 0.25)
			(keepout
				(tracks not_allowed)
				(vias allowed)
				(pads allowed)
				(copperpour not_allowed)
				(footprints allowed)
			)
			(placement
				(enabled no)
				(sheetname "")
			)
			(fill
				(thermal_gap 0.5)
				(thermal_bridge_width 0.5)
				(island_removal_mode 0)
			)
			(polygon
				(pts
					(xy 183.675274 -10.27557) (xy 183.675274 -11.54557) (xy 184.437274 -11.54557) (xy 184.437274 -10.27557)
				)
			)
		)
	)
	(footprint ""
		(layer "F.Cu")
		(at 25.4 -81.026 180)
		(property "Reference" "R1D21"
			(at 0 0 180)
			(layer "F.SilkS")
			(hide yes)
			(effects
				(font
					(size 1.27 1.27)
				)
			)
		)
		(property "Value" ""
			(at 0 0 180)
			(layer "F.Fab")
			(effects
				(font
					(size 1.27 1.27)
				)
			)
		)
		(duplicate_pad_numbers_are_jumpers no)
		(fp_poly
			(pts
				(xy -0.2794 -0.1016) (xy 0.2794 -0.1016) (xy 0.2794 0.9906) (xy -0.2794 0.9906)
			)
			(stroke
				(width 0)
				(type default)
			)
			(fill no)
			(layer "F.CrtYd")
		)
		(fp_line
			(start 0.2794 0.9906)
			(end 0.2794 -0.1016)
			(stroke
				(width 0.1)
				(type default)
			)
			(layer "F.Fab")
		)
		(fp_line
			(start 0.2794 -0.1016)
			(end -0.2794 -0.1016)
			(stroke
				(width 0.1)
				(type default)
			)
			(layer "F.Fab")
		)
		(fp_line
			(start -0.2794 0.9906)
			(end 0.2794 0.9906)
			(stroke
				(width 0.1)
				(type default)
			)
			(layer "F.Fab")
		)
		(fp_line
			(start -0.2794 -0.1016)
			(end -0.2794 0.9906)
			(stroke
				(width 0.1)
				(type default)
			)
			(layer "F.Fab")
		)
		(pad "1" smd rect
			(at 0 0 180)
			(size 0.508 0.508)
			(layers "F.Cu" "F.Mask" "F.Paste")
			(net "P3V3_STBY")
		)
		(pad "2" smd rect
			(at 0 0.889 180)
			(size 0.508 0.508)
			(layers "F.Cu" "F.Mask" "F.Paste")
			(net "FM_OC_DETECT_EN")
		)
		(zone
			(layer "F.Cu")
			(hatch none 0.5)
			(connect_pads
				(clearance 0)
			)
			(min_thickness 0.25)
			(keepout
				(tracks not_allowed)
				(vias allowed)
				(pads allowed)
				(copperpour not_allowed)
				(footprints allowed)
			)
			(placement
				(enabled no)
				(sheetname "")
			)
			(fill
				(thermal_gap 0.5)
				(thermal_bridge_width 0.5)
				(island_removal_mode 0)
			)
			(polygon
				(pts
					(xy 25.654 -81.661) (xy 25.146 -81.661) (xy 25.146 -81.28) (xy 25.654 -81.28)
				)
			)
		)
		(zone
			(layer "F.Cu")
			(hatch none 0.5)
			(connect_pads
				(clearance 0)
			)
			(min_thickness 0.25)
			(keepout
				(tracks allowed)
				(vias not_allowed)
				(pads allowed)
				(copperpour not_allowed)
				(footprints allowed)
			)
			(placement
				(enabled no)
				(sheetname "")
			)
			(fill
				(thermal_gap 0.5)
				(thermal_bridge_width 0.5)
				(island_removal_mode 0)
			)
			(polygon
				(pts
					(xy 25.654 -81.28) (xy 25.146 -81.28) (xy 25.146 -81.661) (xy 25.654 -81.661)
				)
			)
		)
	)
)
